FILE_TYPE = MACRO_DRAWING;
SET COLOR_WIRE YELLOW;
SET COLOR_PROP ORANGE;
SET COLOR_DOT WHITE;
SET COLOR_ARC YELLOW;
SET COLOR_BODY GREEN;
SET COLOR_NOTE PURPLE;
SET PROP_DISPLAY VALUE;
SET PAGE_NUMBER P60;
SET PATH_NUMBER P76;
FORCEADD TDR_3P..2
(-8500 5700);
FORCEPROP 1 LAST PACK_TYPE TH2
J 2
(-8475 5850);
DISPLAY 0.872340 (-8475 5850);
FORCEPROP 1 LAST PATH I1
J 2
(-8200 5850);
DISPLAY 0.872340 (-8200 5850);
PAINT PINK (-8200 5850);
DISPLAY INVISIBLE (-8200 5850);
FORCEPROP 1 LAST CDS_LMAN_SYM_OUTLINE -150,100,50,-100
J 0
(-8500 5700);
DISPLAY 0.468085 (-8500 5700);
PAINT GREEN (-8500 5700);
DISPLAY INVISIBLE (-8500 5700);
FORCEPROP 2 LAST CDS_LIB pure_quanta
J 0
(-8500 5700);
DISPLAY INVISIBLE (-8500 5700);
FORCEPROP 1 LAST PART_NUMBER N_A
J 1
(-8440 5550);
DISPLAY 0.872340 (-8440 5550);
PAINT PINK (-8440 5550);
DISPLAY INVISIBLE (-8440 5550);
FORCEPROP 1 LAST MATERIAL EMPTY
J 2
(-8500 5850);
DISPLAY 0.872340 (-8500 5850);
PAINT PINK (-8500 5850);
DISPLAY INVISIBLE (-8500 5850);
FORCEPROP 2 LAST SEC_TYPE TH2
J 0
(-8475 5950);
DISPLAY 0.680851 (-8475 5950);
DISPLAY INVISIBLE (-8475 5950);
FORCEPROP 1 LAST LOCATION DB1
J 2
(-8475 5900);
DISPLAY 0.872340 (-8475 5900);
PAINT PINK (-8475 5900);
FORCEPROP 0 LASTPIN (-8700 5700) $PN 1
J 2
(-8710 5710);
DISPLAY 0.680851 (-8710 5710);
PAINT MONO (-8710 5710);
FORCEPROP 0 LASTPIN (-8400 5750) $PN 2
J 0
(-8390 5760);
DISPLAY 0.680851 (-8390 5760);
PAINT MONO (-8390 5760);
FORCEPROP 0 LASTPIN (-8400 5650) $PN 3
J 0
(-8390 5660);
DISPLAY 0.680851 (-8390 5660);
PAINT MONO (-8390 5660);
FORCEPROP 2 LAST SEC 1
J 0
(-8475 5950);
DISPLAY 0.680851 (-8475 5950);
PAINT MONO (-8475 5950);
DISPLAY INVISIBLE (-8475 5950);
FORCEADD UNIVERSAL_GND..1
(-8975 4475);
FORCEPROP 3 LASTPIN (-8975 4525) SIG_NAME T_GND\g
J 0
(-8965 4535);
DISPLAY 0.659574 (-8965 4535);
PAINT MONO (-8965 4535);
DISPLAY INVISIBLE (-8965 4535);
FORCEPROP 1 LAST HDL_POWER T_GND
J 1
(-8950 4400);
DISPLAY 0.702128 (-8950 4400);
PAINT GREEN (-8950 4400);
FORCEPROP 1 LAST PATH I10
J 0
(-8900 4475);
DISPLAY 0.872340 (-8900 4475);
PAINT AQUA (-8900 4475);
DISPLAY INVISIBLE (-8900 4475);
FORCEPROP 2 LAST CDS_LIB logical_power
J 0
(-8975 4475);
DISPLAY INVISIBLE (-8975 4475);
FORCEADD TDR_3P..2
(-8500 5225);
FORCEPROP 1 LAST PACK_TYPE TH2
J 2
(-8475 5375);
DISPLAY 0.872340 (-8475 5375);
FORCEPROP 1 LAST PATH I11
J 2
(-8200 5375);
DISPLAY 0.872340 (-8200 5375);
PAINT PINK (-8200 5375);
DISPLAY INVISIBLE (-8200 5375);
FORCEPROP 1 LAST CDS_LMAN_SYM_OUTLINE -150,100,50,-100
J 0
(-8500 5225);
DISPLAY 0.468085 (-8500 5225);
PAINT GREEN (-8500 5225);
DISPLAY INVISIBLE (-8500 5225);
FORCEPROP 2 LAST CDS_LIB pure_quanta
J 0
(-8500 5225);
DISPLAY INVISIBLE (-8500 5225);
FORCEPROP 1 LAST PART_NUMBER N_A
J 1
(-8440 5075);
DISPLAY 0.872340 (-8440 5075);
PAINT PINK (-8440 5075);
DISPLAY INVISIBLE (-8440 5075);
FORCEPROP 1 LAST MATERIAL EMPTY
J 2
(-8500 5375);
DISPLAY 0.872340 (-8500 5375);
PAINT PINK (-8500 5375);
DISPLAY INVISIBLE (-8500 5375);
FORCEPROP 2 LAST SEC_TYPE TH2
J 0
(-8475 5475);
DISPLAY 0.680851 (-8475 5475);
DISPLAY INVISIBLE (-8475 5475);
FORCEPROP 1 LAST LOCATION DB2
J 2
(-8475 5425);
DISPLAY 0.872340 (-8475 5425);
PAINT PINK (-8475 5425);
FORCEPROP 0 LASTPIN (-8700 5225) $PN 1
J 2
(-8710 5235);
DISPLAY 0.680851 (-8710 5235);
PAINT MONO (-8710 5235);
FORCEPROP 0 LASTPIN (-8400 5275) $PN 2
J 0
(-8390 5285);
DISPLAY 0.680851 (-8390 5285);
PAINT MONO (-8390 5285);
FORCEPROP 0 LASTPIN (-8400 5175) $PN 3
J 0
(-8390 5185);
DISPLAY 0.680851 (-8390 5185);
PAINT MONO (-8390 5185);
FORCEPROP 2 LAST SEC 1
J 0
(-8475 5475);
DISPLAY 0.680851 (-8475 5475);
PAINT MONO (-8475 5475);
DISPLAY INVISIBLE (-8475 5475);
FORCEADD UNIVERSAL_GND..1
(-8975 4950);
FORCEPROP 3 LASTPIN (-8975 5000) SIG_NAME T_GND\g
J 0
(-8965 5010);
DISPLAY 0.659574 (-8965 5010);
PAINT MONO (-8965 5010);
DISPLAY INVISIBLE (-8965 5010);
FORCEPROP 1 LAST HDL_POWER T_GND
J 1
(-8950 4875);
DISPLAY 0.702128 (-8950 4875);
PAINT GREEN (-8950 4875);
FORCEPROP 1 LAST PATH I12
J 0
(-8900 4950);
DISPLAY 0.872340 (-8900 4950);
PAINT AQUA (-8900 4950);
DISPLAY INVISIBLE (-8900 4950);
FORCEPROP 2 LAST CDS_LIB logical_power
J 0
(-8975 4950);
DISPLAY INVISIBLE (-8975 4950);
FORCEADD TP_TDR_4P_FTS..1
(-6450 5700);
FORCEPROP 2 LAST PACK_TYPE TH
J 0
(-6575 6025);
DISPLAY 0.680851 (-6575 6025);
FORCEPROP 1 LAST MATERIAL EMPTY
J 0
(-6575 5885);
DISPLAY 0.723404 (-6575 5885);
PAINT GREEN (-6575 5885);
FORCEPROP 2 LAST VALUE TP_TDR_4P_DIP
J 0
(-6575 6075);
DISPLAY 0.680851 (-6575 6075);
FORCEPROP 1 LAST PART_NUMBER TP15
J 0
(-6575 5935);
DISPLAY 0.723404 (-6575 5935);
PAINT GREEN (-6575 5935);
FORCEPROP 1 LAST PATH I13
J 0
(-6350 5880);
DISPLAY 0.723404 (-6350 5880);
PAINT GREEN (-6350 5880);
DISPLAY INVISIBLE (-6350 5880);
FORCEPROP 2 LAST SEC_TYPE TH
J 0
(-6575 6125);
DISPLAY 0.680851 (-6575 6125);
DISPLAY INVISIBLE (-6575 6125);
FORCEPROP 2 LAST CDS_LIB pure_quanta
J 0
(-6450 5700);
DISPLAY INVISIBLE (-6450 5700);
FORCEPROP 1 LAST NEEDS_NO_SIZE TRUE
J 0
(-6450 5700);
DISPLAY 0.468085 (-6450 5700);
PAINT GREEN (-6450 5700);
DISPLAY INVISIBLE (-6450 5700);
FORCEPROP 1 LAST LOCATION X1
J 0
(-6575 5980);
DISPLAY 0.723404 (-6575 5980);
PAINT GREEN (-6575 5980);
FORCEPROP 0 LASTPIN (-6725 5775) $PN 2
J 2
(-6735 5785);
DISPLAY 0.680851 (-6735 5785);
PAINT MONO (-6735 5785);
FORCEPROP 0 LASTPIN (-6725 5625) $PN 3
J 2
(-6735 5635);
DISPLAY 0.680851 (-6735 5635);
PAINT MONO (-6735 5635);
FORCEPROP 0 LASTPIN (-6175 5775) $PN 1
J 0
(-6165 5785);
DISPLAY 0.680851 (-6165 5785);
PAINT MONO (-6165 5785);
FORCEPROP 0 LASTPIN (-6175 5625) $PN 4
J 0
(-6165 5635);
DISPLAY 0.680851 (-6165 5635);
PAINT MONO (-6165 5635);
FORCEPROP 2 LAST SEC 1
J 0
(-6575 6125);
DISPLAY 0.680851 (-6575 6125);
PAINT MONO (-6575 6125);
DISPLAY INVISIBLE (-6575 6125);
FORCEADD TP_TDR_4P_FTS..1
R 4
(-4925 5700);
FORCEPROP 2 LAST PACK_TYPE TH
J 0
(-5050 5975);
DISPLAY 0.680851 (-5050 5975);
FORCEPROP 1 LAST MATERIAL EMPTY
J 0
(-5050 6115);
DISPLAY 0.723404 (-5050 6115);
PAINT GREEN (-5050 6115);
FORCEPROP 1 LAST PART_NUMBER TP15
J 0
(-5050 6065);
DISPLAY 0.723404 (-5050 6065);
PAINT GREEN (-5050 6065);
FORCEPROP 2 LAST VALUE TP_TDR_4P_DIP
J 0
(-5050 5925);
DISPLAY 0.680851 (-5050 5925);
FORCEPROP 1 LAST PATH I14
R 2
J 0
(-5025 5520);
DISPLAY 0.723404 (-5025 5520);
PAINT GREEN (-5025 5520);
DISPLAY INVISIBLE (-5025 5520);
FORCEPROP 1 LAST NEEDS_NO_SIZE TRUE
R 2
J 0
(-4925 5700);
DISPLAY 0.468085 (-4925 5700);
PAINT GREEN (-4925 5700);
DISPLAY INVISIBLE (-4925 5700);
FORCEPROP 2 LAST CDS_LIB pure_quanta
R 2
J 0
(-4925 5700);
DISPLAY INVISIBLE (-4925 5700);
FORCEPROP 2 LAST SEC_TYPE TH
R 2
J 0
(-4800 5275);
DISPLAY 0.680851 (-4800 5275);
DISPLAY INVISIBLE (-4800 5275);
FORCEPROP 1 LAST LOCATION X7
J 0
(-5050 6020);
DISPLAY 0.723404 (-5050 6020);
PAINT GREEN (-5050 6020);
FORCEPROP 0 LASTPIN (-4650 5625) $PN 2
J 0
(-4640 5635);
DISPLAY 0.680851 (-4640 5635);
PAINT MONO (-4640 5635);
FORCEPROP 0 LASTPIN (-4650 5775) $PN 3
J 0
(-4640 5785);
DISPLAY 0.680851 (-4640 5785);
PAINT MONO (-4640 5785);
FORCEPROP 0 LASTPIN (-5200 5625) $PN 1
J 2
(-5210 5635);
DISPLAY 0.680851 (-5210 5635);
PAINT MONO (-5210 5635);
FORCEPROP 0 LASTPIN (-5200 5775) $PN 4
J 2
(-5210 5785);
DISPLAY 0.680851 (-5210 5785);
PAINT MONO (-5210 5785);
FORCEPROP 2 LAST SEC 1
R 2
J 0
(-4800 5275);
DISPLAY 0.680851 (-4800 5275);
PAINT MONO (-4800 5275);
DISPLAY INVISIBLE (-4800 5275);
FORCEADD TP_TDR_4P_FTS..1
R 4
(-4925 2200);
FORCEPROP 1 LAST PART_NUMBER TP15
J 0
(-5050 2565);
DISPLAY 0.723404 (-5050 2565);
PAINT GREEN (-5050 2565);
FORCEPROP 2 LAST VALUE TP_TDR_4P_DIP
J 0
(-5050 2425);
DISPLAY 0.680851 (-5050 2425);
FORCEPROP 1 LAST MATERIAL EMPTY
J 0
(-5050 2615);
DISPLAY 0.723404 (-5050 2615);
PAINT GREEN (-5050 2615);
FORCEPROP 2 LAST PACK_TYPE TH
J 0
(-5050 2475);
DISPLAY 0.680851 (-5050 2475);
FORCEPROP 1 LAST PATH I18
R 2
J 0
(-5025 2020);
DISPLAY 0.723404 (-5025 2020);
PAINT GREEN (-5025 2020);
DISPLAY INVISIBLE (-5025 2020);
FORCEPROP 2 LAST SEC_TYPE TH
R 2
J 0
(-4800 1775);
DISPLAY 0.680851 (-4800 1775);
DISPLAY INVISIBLE (-4800 1775);
FORCEPROP 2 LAST CDS_LIB pure_quanta
R 2
J 0
(-4925 2200);
DISPLAY INVISIBLE (-4925 2200);
FORCEPROP 1 LAST NEEDS_NO_SIZE TRUE
R 2
J 0
(-4925 2200);
DISPLAY 0.468085 (-4925 2200);
PAINT GREEN (-4925 2200);
DISPLAY INVISIBLE (-4925 2200);
FORCEPROP 1 LAST LOCATION X12
J 0
(-5050 2520);
DISPLAY 0.723404 (-5050 2520);
PAINT GREEN (-5050 2520);
FORCEPROP 0 LASTPIN (-4650 2125) $PN 2
J 0
(-4640 2135);
DISPLAY 0.680851 (-4640 2135);
PAINT MONO (-4640 2135);
FORCEPROP 0 LASTPIN (-4650 2275) $PN 3
J 0
(-4640 2285);
DISPLAY 0.680851 (-4640 2285);
PAINT MONO (-4640 2285);
FORCEPROP 0 LASTPIN (-5200 2125) $PN 1
J 2
(-5210 2135);
DISPLAY 0.680851 (-5210 2135);
PAINT MONO (-5210 2135);
FORCEPROP 0 LASTPIN (-5200 2275) $PN 4
J 2
(-5210 2285);
DISPLAY 0.680851 (-5210 2285);
PAINT MONO (-5210 2285);
FORCEPROP 2 LAST SEC 1
R 2
J 0
(-4800 1775);
DISPLAY 0.680851 (-4800 1775);
PAINT MONO (-4800 1775);
DISPLAY INVISIBLE (-4800 1775);
FORCEADD TP_TDR_4P_FTS..1
(-6450 2200);
FORCEPROP 1 LAST PART_NUMBER TP15
J 0
(-6575 2435);
DISPLAY 0.723404 (-6575 2435);
PAINT GREEN (-6575 2435);
FORCEPROP 2 LAST VALUE TP_TDR_4P_DIP
J 0
(-6575 2575);
DISPLAY 0.680851 (-6575 2575);
FORCEPROP 1 LAST MATERIAL EMPTY
J 0
(-6575 2385);
DISPLAY 0.723404 (-6575 2385);
PAINT GREEN (-6575 2385);
FORCEPROP 2 LAST PACK_TYPE TH
J 0
(-6575 2525);
DISPLAY 0.680851 (-6575 2525);
FORCEPROP 1 LAST PATH I19
J 0
(-6350 2380);
DISPLAY 0.723404 (-6350 2380);
PAINT GREEN (-6350 2380);
DISPLAY INVISIBLE (-6350 2380);
FORCEPROP 1 LAST NEEDS_NO_SIZE TRUE
J 0
(-6450 2200);
DISPLAY 0.468085 (-6450 2200);
PAINT GREEN (-6450 2200);
DISPLAY INVISIBLE (-6450 2200);
FORCEPROP 2 LAST CDS_LIB pure_quanta
J 0
(-6450 2200);
DISPLAY INVISIBLE (-6450 2200);
FORCEPROP 2 LAST SEC_TYPE TH
J 0
(-6575 2625);
DISPLAY 0.680851 (-6575 2625);
DISPLAY INVISIBLE (-6575 2625);
FORCEPROP 1 LAST LOCATION X6
J 0
(-6575 2480);
DISPLAY 0.723404 (-6575 2480);
PAINT GREEN (-6575 2480);
FORCEPROP 0 LASTPIN (-6725 2275) $PN 2
J 2
(-6735 2285);
DISPLAY 0.680851 (-6735 2285);
PAINT MONO (-6735 2285);
FORCEPROP 0 LASTPIN (-6725 2125) $PN 3
J 2
(-6735 2135);
DISPLAY 0.680851 (-6735 2135);
PAINT MONO (-6735 2135);
FORCEPROP 0 LASTPIN (-6175 2275) $PN 1
J 0
(-6165 2285);
DISPLAY 0.680851 (-6165 2285);
PAINT MONO (-6165 2285);
FORCEPROP 0 LASTPIN (-6175 2125) $PN 4
J 0
(-6165 2135);
DISPLAY 0.680851 (-6165 2135);
PAINT MONO (-6165 2135);
FORCEPROP 2 LAST SEC 1
J 0
(-6575 2625);
DISPLAY 0.680851 (-6575 2625);
PAINT MONO (-6575 2625);
DISPLAY INVISIBLE (-6575 2625);
FORCEADD UNIVERSAL_GND..1
(-8975 5425);
FORCEPROP 3 LASTPIN (-8975 5475) SIG_NAME T_GND\g
J 0
(-8965 5485);
DISPLAY 0.659574 (-8965 5485);
PAINT MONO (-8965 5485);
DISPLAY INVISIBLE (-8965 5485);
FORCEPROP 1 LAST HDL_POWER T_GND
J 1
(-8950 5350);
DISPLAY 0.702128 (-8950 5350);
PAINT GREEN (-8950 5350);
FORCEPROP 1 LAST PATH I2
J 0
(-8900 5425);
DISPLAY 0.872340 (-8900 5425);
PAINT AQUA (-8900 5425);
DISPLAY INVISIBLE (-8900 5425);
FORCEPROP 2 LAST CDS_LIB logical_power
J 0
(-8975 5425);
DISPLAY INVISIBLE (-8975 5425);
FORCEADD TP_TDR_4P_FTS..1
R 4
(-4925 2900);
FORCEPROP 1 LAST PART_NUMBER TP15
J 0
(-5050 3265);
DISPLAY 0.723404 (-5050 3265);
PAINT GREEN (-5050 3265);
FORCEPROP 2 LAST VALUE TP_TDR_4P_DIP
J 0
(-5050 3125);
DISPLAY 0.680851 (-5050 3125);
FORCEPROP 1 LAST MATERIAL EMPTY
J 0
(-5050 3315);
DISPLAY 0.723404 (-5050 3315);
PAINT GREEN (-5050 3315);
FORCEPROP 2 LAST PACK_TYPE TH
J 0
(-5050 3175);
DISPLAY 0.680851 (-5050 3175);
FORCEPROP 1 LAST PATH I22
R 2
J 0
(-5025 2720);
DISPLAY 0.723404 (-5025 2720);
PAINT GREEN (-5025 2720);
DISPLAY INVISIBLE (-5025 2720);
FORCEPROP 2 LAST SEC_TYPE TH
R 2
J 0
(-4800 2475);
DISPLAY 0.680851 (-4800 2475);
DISPLAY INVISIBLE (-4800 2475);
FORCEPROP 2 LAST CDS_LIB pure_quanta
R 2
J 0
(-4925 2900);
DISPLAY INVISIBLE (-4925 2900);
FORCEPROP 1 LAST NEEDS_NO_SIZE TRUE
R 2
J 0
(-4925 2900);
DISPLAY 0.468085 (-4925 2900);
PAINT GREEN (-4925 2900);
DISPLAY INVISIBLE (-4925 2900);
FORCEPROP 1 LAST LOCATION X11
J 0
(-5050 3220);
DISPLAY 0.723404 (-5050 3220);
PAINT GREEN (-5050 3220);
FORCEPROP 0 LASTPIN (-4650 2825) $PN 2
J 0
(-4640 2835);
DISPLAY 0.680851 (-4640 2835);
PAINT MONO (-4640 2835);
FORCEPROP 0 LASTPIN (-4650 2975) $PN 3
J 0
(-4640 2985);
DISPLAY 0.680851 (-4640 2985);
PAINT MONO (-4640 2985);
FORCEPROP 0 LASTPIN (-5200 2825) $PN 1
J 2
(-5210 2835);
DISPLAY 0.680851 (-5210 2835);
PAINT MONO (-5210 2835);
FORCEPROP 0 LASTPIN (-5200 2975) $PN 4
J 2
(-5210 2985);
DISPLAY 0.680851 (-5210 2985);
PAINT MONO (-5210 2985);
FORCEPROP 2 LAST SEC 1
R 2
J 0
(-4800 2475);
DISPLAY 0.680851 (-4800 2475);
PAINT MONO (-4800 2475);
DISPLAY INVISIBLE (-4800 2475);
FORCEADD TP_TDR_4P_FTS..1
(-6450 2900);
FORCEPROP 1 LAST PART_NUMBER TP15
J 0
(-6575 3135);
DISPLAY 0.723404 (-6575 3135);
PAINT GREEN (-6575 3135);
FORCEPROP 2 LAST VALUE TP_TDR_4P_DIP
J 0
(-6575 3275);
DISPLAY 0.680851 (-6575 3275);
FORCEPROP 1 LAST MATERIAL EMPTY
J 0
(-6575 3085);
DISPLAY 0.723404 (-6575 3085);
PAINT GREEN (-6575 3085);
FORCEPROP 2 LAST PACK_TYPE TH
J 0
(-6575 3225);
DISPLAY 0.680851 (-6575 3225);
FORCEPROP 1 LAST PATH I23
J 0
(-6350 3080);
DISPLAY 0.723404 (-6350 3080);
PAINT GREEN (-6350 3080);
DISPLAY INVISIBLE (-6350 3080);
FORCEPROP 1 LAST NEEDS_NO_SIZE TRUE
J 0
(-6450 2900);
DISPLAY 0.468085 (-6450 2900);
PAINT GREEN (-6450 2900);
DISPLAY INVISIBLE (-6450 2900);
FORCEPROP 2 LAST CDS_LIB pure_quanta
J 0
(-6450 2900);
DISPLAY INVISIBLE (-6450 2900);
FORCEPROP 2 LAST SEC_TYPE TH
J 0
(-6575 3325);
DISPLAY 0.680851 (-6575 3325);
DISPLAY INVISIBLE (-6575 3325);
FORCEPROP 1 LAST LOCATION X5
J 0
(-6575 3180);
DISPLAY 0.723404 (-6575 3180);
PAINT GREEN (-6575 3180);
FORCEPROP 0 LASTPIN (-6725 2975) $PN 2
J 2
(-6735 2985);
DISPLAY 0.680851 (-6735 2985);
PAINT MONO (-6735 2985);
FORCEPROP 0 LASTPIN (-6725 2825) $PN 3
J 2
(-6735 2835);
DISPLAY 0.680851 (-6735 2835);
PAINT MONO (-6735 2835);
FORCEPROP 0 LASTPIN (-6175 2975) $PN 1
J 0
(-6165 2985);
DISPLAY 0.680851 (-6165 2985);
PAINT MONO (-6165 2985);
FORCEPROP 0 LASTPIN (-6175 2825) $PN 4
J 0
(-6165 2835);
DISPLAY 0.680851 (-6165 2835);
PAINT MONO (-6165 2835);
FORCEPROP 2 LAST SEC 1
J 0
(-6575 3325);
DISPLAY 0.680851 (-6575 3325);
PAINT MONO (-6575 3325);
DISPLAY INVISIBLE (-6575 3325);
FORCEADD TDR_3P..2
(-8500 3325);
FORCEPROP 1 LAST PACK_TYPE TH2
J 2
(-8475 3475);
DISPLAY 0.872340 (-8475 3475);
FORCEPROP 1 LAST PATH I3
J 2
(-8200 3475);
DISPLAY 0.872340 (-8200 3475);
PAINT PINK (-8200 3475);
DISPLAY INVISIBLE (-8200 3475);
FORCEPROP 1 LAST CDS_LMAN_SYM_OUTLINE -150,100,50,-100
J 0
(-8500 3325);
DISPLAY 0.468085 (-8500 3325);
PAINT GREEN (-8500 3325);
DISPLAY INVISIBLE (-8500 3325);
FORCEPROP 2 LAST CDS_LIB pure_quanta
J 0
(-8500 3325);
DISPLAY INVISIBLE (-8500 3325);
FORCEPROP 1 LAST PART_NUMBER N_A
J 1
(-8440 3175);
DISPLAY 0.872340 (-8440 3175);
PAINT PINK (-8440 3175);
DISPLAY INVISIBLE (-8440 3175);
FORCEPROP 1 LAST MATERIAL EMPTY
J 2
(-8500 3475);
DISPLAY 0.872340 (-8500 3475);
PAINT PINK (-8500 3475);
DISPLAY INVISIBLE (-8500 3475);
FORCEPROP 2 LAST SEC_TYPE TH2
J 0
(-8475 3575);
DISPLAY 0.680851 (-8475 3575);
DISPLAY INVISIBLE (-8475 3575);
FORCEPROP 1 LAST LOCATION DB6
J 2
(-8475 3525);
DISPLAY 0.872340 (-8475 3525);
PAINT PINK (-8475 3525);
FORCEPROP 0 LASTPIN (-8700 3325) $PN 1
J 2
(-8710 3335);
DISPLAY 0.680851 (-8710 3335);
PAINT MONO (-8710 3335);
FORCEPROP 0 LASTPIN (-8400 3375) $PN 2
J 0
(-8390 3385);
DISPLAY 0.680851 (-8390 3385);
PAINT MONO (-8390 3385);
FORCEPROP 0 LASTPIN (-8400 3275) $PN 3
J 0
(-8390 3285);
DISPLAY 0.680851 (-8390 3285);
PAINT MONO (-8390 3285);
FORCEPROP 2 LAST SEC 1
J 0
(-8475 3575);
DISPLAY 0.680851 (-8475 3575);
PAINT MONO (-8475 3575);
DISPLAY INVISIBLE (-8475 3575);
FORCEADD TP_TDR_4P_FTS..1
R 4
(-4925 5000);
FORCEPROP 1 LAST PART_NUMBER TP15
J 0
(-5050 5365);
DISPLAY 0.723404 (-5050 5365);
PAINT GREEN (-5050 5365);
FORCEPROP 2 LAST VALUE TP_TDR_4P_DIP
J 0
(-5050 5225);
DISPLAY 0.680851 (-5050 5225);
FORCEPROP 1 LAST MATERIAL EMPTY
J 0
(-5050 5415);
DISPLAY 0.723404 (-5050 5415);
PAINT GREEN (-5050 5415);
FORCEPROP 2 LAST PACK_TYPE TH
J 0
(-5050 5275);
DISPLAY 0.680851 (-5050 5275);
FORCEPROP 1 LAST PATH I34
R 2
J 0
(-5025 4820);
DISPLAY 0.723404 (-5025 4820);
PAINT GREEN (-5025 4820);
DISPLAY INVISIBLE (-5025 4820);
FORCEPROP 2 LAST SEC_TYPE TH
R 2
J 0
(-4800 4575);
DISPLAY 0.680851 (-4800 4575);
DISPLAY INVISIBLE (-4800 4575);
FORCEPROP 2 LAST CDS_LIB pure_quanta
R 2
J 0
(-4925 5000);
DISPLAY INVISIBLE (-4925 5000);
FORCEPROP 1 LAST NEEDS_NO_SIZE TRUE
R 2
J 0
(-4925 5000);
DISPLAY 0.468085 (-4925 5000);
PAINT GREEN (-4925 5000);
DISPLAY INVISIBLE (-4925 5000);
FORCEPROP 1 LAST LOCATION X8
J 0
(-5050 5320);
DISPLAY 0.723404 (-5050 5320);
PAINT GREEN (-5050 5320);
FORCEPROP 0 LASTPIN (-4650 4925) $PN 2
J 0
(-4640 4935);
DISPLAY 0.680851 (-4640 4935);
PAINT MONO (-4640 4935);
FORCEPROP 0 LASTPIN (-4650 5075) $PN 3
J 0
(-4640 5085);
DISPLAY 0.680851 (-4640 5085);
PAINT MONO (-4640 5085);
FORCEPROP 0 LASTPIN (-5200 4925) $PN 1
J 2
(-5210 4935);
DISPLAY 0.680851 (-5210 4935);
PAINT MONO (-5210 4935);
FORCEPROP 0 LASTPIN (-5200 5075) $PN 4
J 2
(-5210 5085);
DISPLAY 0.680851 (-5210 5085);
PAINT MONO (-5210 5085);
FORCEPROP 2 LAST SEC 1
R 2
J 0
(-4800 4575);
DISPLAY 0.680851 (-4800 4575);
PAINT MONO (-4800 4575);
DISPLAY INVISIBLE (-4800 4575);
FORCEADD TP_TDR_4P_FTS..1
(-6450 5000);
FORCEPROP 1 LAST PART_NUMBER TP15
J 0
(-6575 5235);
DISPLAY 0.723404 (-6575 5235);
PAINT GREEN (-6575 5235);
FORCEPROP 2 LAST VALUE TP_TDR_4P_DIP
J 0
(-6575 5375);
DISPLAY 0.680851 (-6575 5375);
FORCEPROP 1 LAST MATERIAL EMPTY
J 0
(-6575 5185);
DISPLAY 0.723404 (-6575 5185);
PAINT GREEN (-6575 5185);
FORCEPROP 2 LAST PACK_TYPE TH
J 0
(-6575 5325);
DISPLAY 0.680851 (-6575 5325);
FORCEPROP 1 LAST PATH I35
J 0
(-6350 5180);
DISPLAY 0.723404 (-6350 5180);
PAINT GREEN (-6350 5180);
DISPLAY INVISIBLE (-6350 5180);
FORCEPROP 1 LAST NEEDS_NO_SIZE TRUE
J 0
(-6450 5000);
DISPLAY 0.468085 (-6450 5000);
PAINT GREEN (-6450 5000);
DISPLAY INVISIBLE (-6450 5000);
FORCEPROP 2 LAST CDS_LIB pure_quanta
J 0
(-6450 5000);
DISPLAY INVISIBLE (-6450 5000);
FORCEPROP 2 LAST SEC_TYPE TH
J 0
(-6575 5425);
DISPLAY 0.680851 (-6575 5425);
DISPLAY INVISIBLE (-6575 5425);
FORCEPROP 1 LAST LOCATION X2
J 0
(-6575 5280);
DISPLAY 0.723404 (-6575 5280);
PAINT GREEN (-6575 5280);
FORCEPROP 0 LASTPIN (-6725 5075) $PN 2
J 2
(-6735 5085);
DISPLAY 0.680851 (-6735 5085);
PAINT MONO (-6735 5085);
FORCEPROP 0 LASTPIN (-6725 4925) $PN 3
J 2
(-6735 4935);
DISPLAY 0.680851 (-6735 4935);
PAINT MONO (-6735 4935);
FORCEPROP 0 LASTPIN (-6175 5075) $PN 1
J 0
(-6165 5085);
DISPLAY 0.680851 (-6165 5085);
PAINT MONO (-6165 5085);
FORCEPROP 0 LASTPIN (-6175 4925) $PN 4
J 0
(-6165 4935);
DISPLAY 0.680851 (-6165 4935);
PAINT MONO (-6165 4935);
FORCEPROP 2 LAST SEC 1
J 0
(-6575 5425);
DISPLAY 0.680851 (-6575 5425);
PAINT MONO (-6575 5425);
DISPLAY INVISIBLE (-6575 5425);
FORCEADD TP_TDR_4P_FTS..1
R 4
(-1800 5700);
FORCEPROP 1 LAST PART_NUMBER TP15
J 0
(-1925 6065);
DISPLAY 0.723404 (-1925 6065);
PAINT GREEN (-1925 6065);
FORCEPROP 2 LAST VALUE TP_TDR_4P_DIP
J 0
(-1925 5925);
DISPLAY 0.680851 (-1925 5925);
FORCEPROP 1 LAST MATERIAL EMPTY
J 0
(-1925 6115);
DISPLAY 0.723404 (-1925 6115);
PAINT GREEN (-1925 6115);
FORCEPROP 2 LAST PACK_TYPE TH
J 0
(-1925 5975);
DISPLAY 0.680851 (-1925 5975);
FORCEPROP 1 LAST PATH I38
R 2
J 0
(-1900 5520);
DISPLAY 0.723404 (-1900 5520);
PAINT GREEN (-1900 5520);
DISPLAY INVISIBLE (-1900 5520);
FORCEPROP 2 LAST SEC_TYPE TH
R 2
J 0
(-1675 5275);
DISPLAY 0.680851 (-1675 5275);
DISPLAY INVISIBLE (-1675 5275);
FORCEPROP 2 LAST CDS_LIB pure_quanta
R 2
J 0
(-1800 5700);
DISPLAY INVISIBLE (-1800 5700);
FORCEPROP 1 LAST NEEDS_NO_SIZE TRUE
R 2
J 0
(-1800 5700);
DISPLAY 0.468085 (-1800 5700);
PAINT GREEN (-1800 5700);
DISPLAY INVISIBLE (-1800 5700);
FORCEPROP 1 LAST LOCATION X19
J 0
(-1925 6020);
DISPLAY 0.723404 (-1925 6020);
PAINT GREEN (-1925 6020);
FORCEPROP 0 LASTPIN (-1525 5625) $PN 2
J 0
(-1515 5635);
DISPLAY 0.680851 (-1515 5635);
PAINT MONO (-1515 5635);
FORCEPROP 0 LASTPIN (-1525 5775) $PN 3
J 0
(-1515 5785);
DISPLAY 0.680851 (-1515 5785);
PAINT MONO (-1515 5785);
FORCEPROP 0 LASTPIN (-2075 5625) $PN 1
J 2
(-2085 5635);
DISPLAY 0.680851 (-2085 5635);
PAINT MONO (-2085 5635);
FORCEPROP 0 LASTPIN (-2075 5775) $PN 4
J 2
(-2085 5785);
DISPLAY 0.680851 (-2085 5785);
PAINT MONO (-2085 5785);
FORCEPROP 2 LAST SEC 1
R 2
J 0
(-1675 5275);
DISPLAY 0.680851 (-1675 5275);
PAINT MONO (-1675 5275);
DISPLAY INVISIBLE (-1675 5275);
FORCEADD TP_TDR_4P_FTS..1
(-3325 5700);
FORCEPROP 1 LAST PART_NUMBER TP15
J 0
(-3450 5935);
DISPLAY 0.723404 (-3450 5935);
PAINT GREEN (-3450 5935);
FORCEPROP 1 LAST MATERIAL EMPTY
J 0
(-3450 5885);
DISPLAY 0.723404 (-3450 5885);
PAINT GREEN (-3450 5885);
FORCEPROP 2 LAST PACK_TYPE TH
J 0
(-3450 6025);
DISPLAY 0.680851 (-3450 6025);
FORCEPROP 2 LAST VALUE TP_TDR_4P_DIP
J 0
(-3450 6075);
DISPLAY 0.680851 (-3450 6075);
FORCEPROP 1 LAST PATH I39
J 0
(-3225 5880);
DISPLAY 0.723404 (-3225 5880);
PAINT GREEN (-3225 5880);
DISPLAY INVISIBLE (-3225 5880);
FORCEPROP 1 LAST NEEDS_NO_SIZE TRUE
J 0
(-3325 5700);
DISPLAY 0.468085 (-3325 5700);
PAINT GREEN (-3325 5700);
DISPLAY INVISIBLE (-3325 5700);
FORCEPROP 2 LAST CDS_LIB pure_quanta
J 0
(-3325 5700);
DISPLAY INVISIBLE (-3325 5700);
FORCEPROP 2 LAST SEC_TYPE TH
J 0
(-3450 6125);
DISPLAY 0.680851 (-3450 6125);
DISPLAY INVISIBLE (-3450 6125);
FORCEPROP 1 LAST LOCATION X13
J 0
(-3450 5980);
DISPLAY 0.723404 (-3450 5980);
PAINT GREEN (-3450 5980);
FORCEPROP 0 LASTPIN (-3600 5775) $PN 2
J 2
(-3610 5785);
DISPLAY 0.680851 (-3610 5785);
PAINT MONO (-3610 5785);
FORCEPROP 0 LASTPIN (-3600 5625) $PN 3
J 2
(-3610 5635);
DISPLAY 0.680851 (-3610 5635);
PAINT MONO (-3610 5635);
FORCEPROP 0 LASTPIN (-3050 5775) $PN 1
J 0
(-3040 5785);
DISPLAY 0.680851 (-3040 5785);
PAINT MONO (-3040 5785);
FORCEPROP 0 LASTPIN (-3050 5625) $PN 4
J 0
(-3040 5635);
DISPLAY 0.680851 (-3040 5635);
PAINT MONO (-3040 5635);
FORCEPROP 2 LAST SEC 1
J 0
(-3450 6125);
DISPLAY 0.680851 (-3450 6125);
PAINT MONO (-3450 6125);
DISPLAY INVISIBLE (-3450 6125);
FORCEADD UNIVERSAL_GND..1
(-8975 3050);
FORCEPROP 3 LASTPIN (-8975 3100) SIG_NAME T_GND\g
J 0
(-8965 3110);
DISPLAY 0.659574 (-8965 3110);
PAINT MONO (-8965 3110);
DISPLAY INVISIBLE (-8965 3110);
FORCEPROP 1 LAST HDL_POWER T_GND
J 1
(-8950 2975);
DISPLAY 0.702128 (-8950 2975);
PAINT GREEN (-8950 2975);
FORCEPROP 1 LAST PATH I4
J 0
(-8900 3050);
DISPLAY 0.872340 (-8900 3050);
PAINT AQUA (-8900 3050);
DISPLAY INVISIBLE (-8900 3050);
FORCEPROP 2 LAST CDS_LIB logical_power
J 0
(-8975 3050);
DISPLAY INVISIBLE (-8975 3050);
FORCEADD TP_TDR_4P_FTS..1
(-3325 2200);
FORCEPROP 2 LAST PACK_TYPE TH
J 0
(-3450 2525);
DISPLAY 0.680851 (-3450 2525);
FORCEPROP 1 LAST MATERIAL EMPTY
J 0
(-3450 2385);
DISPLAY 0.723404 (-3450 2385);
PAINT GREEN (-3450 2385);
FORCEPROP 2 LAST VALUE TP_TDR_4P_DIP
J 0
(-3450 2575);
DISPLAY 0.680851 (-3450 2575);
FORCEPROP 1 LAST PART_NUMBER TP15
J 0
(-3450 2435);
DISPLAY 0.723404 (-3450 2435);
PAINT GREEN (-3450 2435);
FORCEPROP 1 LAST PATH I42
J 0
(-3225 2380);
DISPLAY 0.723404 (-3225 2380);
PAINT GREEN (-3225 2380);
DISPLAY INVISIBLE (-3225 2380);
FORCEPROP 2 LAST SEC_TYPE TH
J 0
(-3450 2625);
DISPLAY 0.680851 (-3450 2625);
DISPLAY INVISIBLE (-3450 2625);
FORCEPROP 2 LAST CDS_LIB pure_quanta
J 0
(-3325 2200);
DISPLAY INVISIBLE (-3325 2200);
FORCEPROP 1 LAST NEEDS_NO_SIZE TRUE
J 0
(-3325 2200);
DISPLAY 0.468085 (-3325 2200);
PAINT GREEN (-3325 2200);
DISPLAY INVISIBLE (-3325 2200);
FORCEPROP 1 LAST LOCATION X18
J 0
(-3450 2480);
DISPLAY 0.723404 (-3450 2480);
PAINT GREEN (-3450 2480);
FORCEPROP 0 LASTPIN (-3600 2275) $PN 2
J 2
(-3610 2285);
DISPLAY 0.680851 (-3610 2285);
PAINT MONO (-3610 2285);
FORCEPROP 0 LASTPIN (-3600 2125) $PN 3
J 2
(-3610 2135);
DISPLAY 0.680851 (-3610 2135);
PAINT MONO (-3610 2135);
FORCEPROP 0 LASTPIN (-3050 2275) $PN 1
J 0
(-3040 2285);
DISPLAY 0.680851 (-3040 2285);
PAINT MONO (-3040 2285);
FORCEPROP 0 LASTPIN (-3050 2125) $PN 4
J 0
(-3040 2135);
DISPLAY 0.680851 (-3040 2135);
PAINT MONO (-3040 2135);
FORCEPROP 2 LAST SEC 1
J 0
(-3450 2625);
DISPLAY 0.680851 (-3450 2625);
PAINT MONO (-3450 2625);
DISPLAY INVISIBLE (-3450 2625);
FORCEADD TP_TDR_4P_FTS..1
R 4
(-1800 2200);
FORCEPROP 2 LAST PACK_TYPE TH
J 0
(-1925 2475);
DISPLAY 0.680851 (-1925 2475);
FORCEPROP 1 LAST MATERIAL EMPTY
J 0
(-1925 2615);
DISPLAY 0.723404 (-1925 2615);
PAINT GREEN (-1925 2615);
FORCEPROP 2 LAST VALUE TP_TDR_4P_DIP
J 0
(-1925 2425);
DISPLAY 0.680851 (-1925 2425);
FORCEPROP 1 LAST PART_NUMBER TP15
J 0
(-1925 2565);
DISPLAY 0.723404 (-1925 2565);
PAINT GREEN (-1925 2565);
FORCEPROP 1 LAST PATH I43
R 2
J 0
(-1900 2020);
DISPLAY 0.723404 (-1900 2020);
PAINT GREEN (-1900 2020);
DISPLAY INVISIBLE (-1900 2020);
FORCEPROP 1 LAST NEEDS_NO_SIZE TRUE
R 2
J 0
(-1800 2200);
DISPLAY 0.468085 (-1800 2200);
PAINT GREEN (-1800 2200);
DISPLAY INVISIBLE (-1800 2200);
FORCEPROP 2 LAST CDS_LIB pure_quanta
R 2
J 0
(-1800 2200);
DISPLAY INVISIBLE (-1800 2200);
FORCEPROP 2 LAST SEC_TYPE TH
R 2
J 0
(-1675 1775);
DISPLAY 0.680851 (-1675 1775);
DISPLAY INVISIBLE (-1675 1775);
FORCEPROP 1 LAST LOCATION X24
J 0
(-1925 2520);
DISPLAY 0.723404 (-1925 2520);
PAINT GREEN (-1925 2520);
FORCEPROP 0 LASTPIN (-1525 2125) $PN 2
J 0
(-1515 2135);
DISPLAY 0.680851 (-1515 2135);
PAINT MONO (-1515 2135);
FORCEPROP 0 LASTPIN (-1525 2275) $PN 3
J 0
(-1515 2285);
DISPLAY 0.680851 (-1515 2285);
PAINT MONO (-1515 2285);
FORCEPROP 0 LASTPIN (-2075 2125) $PN 1
J 2
(-2085 2135);
DISPLAY 0.680851 (-2085 2135);
PAINT MONO (-2085 2135);
FORCEPROP 0 LASTPIN (-2075 2275) $PN 4
J 2
(-2085 2285);
DISPLAY 0.680851 (-2085 2285);
PAINT MONO (-2085 2285);
FORCEPROP 2 LAST SEC 1
R 2
J 0
(-1675 1775);
DISPLAY 0.680851 (-1675 1775);
PAINT MONO (-1675 1775);
DISPLAY INVISIBLE (-1675 1775);
FORCEADD TP_TDR_4P_FTS..1
(-3325 2900);
FORCEPROP 2 LAST PACK_TYPE TH
J 0
(-3450 3225);
DISPLAY 0.680851 (-3450 3225);
FORCEPROP 1 LAST MATERIAL EMPTY
J 0
(-3450 3085);
DISPLAY 0.723404 (-3450 3085);
PAINT GREEN (-3450 3085);
FORCEPROP 2 LAST VALUE TP_TDR_4P_DIP
J 0
(-3450 3275);
DISPLAY 0.680851 (-3450 3275);
FORCEPROP 1 LAST PART_NUMBER TP15
J 0
(-3450 3135);
DISPLAY 0.723404 (-3450 3135);
PAINT GREEN (-3450 3135);
FORCEPROP 1 LAST PATH I46
J 0
(-3225 3080);
DISPLAY 0.723404 (-3225 3080);
PAINT GREEN (-3225 3080);
DISPLAY INVISIBLE (-3225 3080);
FORCEPROP 2 LAST SEC_TYPE TH
J 0
(-3450 3325);
DISPLAY 0.680851 (-3450 3325);
DISPLAY INVISIBLE (-3450 3325);
FORCEPROP 2 LAST CDS_LIB pure_quanta
J 0
(-3325 2900);
DISPLAY INVISIBLE (-3325 2900);
FORCEPROP 1 LAST NEEDS_NO_SIZE TRUE
J 0
(-3325 2900);
DISPLAY 0.468085 (-3325 2900);
PAINT GREEN (-3325 2900);
DISPLAY INVISIBLE (-3325 2900);
FORCEPROP 1 LAST LOCATION X17
J 0
(-3450 3180);
DISPLAY 0.723404 (-3450 3180);
PAINT GREEN (-3450 3180);
FORCEPROP 0 LASTPIN (-3600 2975) $PN 2
J 2
(-3610 2985);
DISPLAY 0.680851 (-3610 2985);
PAINT MONO (-3610 2985);
FORCEPROP 0 LASTPIN (-3600 2825) $PN 3
J 2
(-3610 2835);
DISPLAY 0.680851 (-3610 2835);
PAINT MONO (-3610 2835);
FORCEPROP 0 LASTPIN (-3050 2975) $PN 1
J 0
(-3040 2985);
DISPLAY 0.680851 (-3040 2985);
PAINT MONO (-3040 2985);
FORCEPROP 0 LASTPIN (-3050 2825) $PN 4
J 0
(-3040 2835);
DISPLAY 0.680851 (-3040 2835);
PAINT MONO (-3040 2835);
FORCEPROP 2 LAST SEC 1
J 0
(-3450 3325);
DISPLAY 0.680851 (-3450 3325);
PAINT MONO (-3450 3325);
DISPLAY INVISIBLE (-3450 3325);
FORCEADD TP_TDR_4P_FTS..1
R 4
(-1800 2900);
FORCEPROP 2 LAST PACK_TYPE TH
J 0
(-1925 3175);
DISPLAY 0.680851 (-1925 3175);
FORCEPROP 1 LAST MATERIAL EMPTY
J 0
(-1925 3315);
DISPLAY 0.723404 (-1925 3315);
PAINT GREEN (-1925 3315);
FORCEPROP 2 LAST VALUE TP_TDR_4P_DIP
J 0
(-1925 3125);
DISPLAY 0.680851 (-1925 3125);
FORCEPROP 1 LAST PART_NUMBER TP15
J 0
(-1925 3265);
DISPLAY 0.723404 (-1925 3265);
PAINT GREEN (-1925 3265);
FORCEPROP 1 LAST PATH I47
R 2
J 0
(-1900 2720);
DISPLAY 0.723404 (-1900 2720);
PAINT GREEN (-1900 2720);
DISPLAY INVISIBLE (-1900 2720);
FORCEPROP 1 LAST NEEDS_NO_SIZE TRUE
R 2
J 0
(-1800 2900);
DISPLAY 0.468085 (-1800 2900);
PAINT GREEN (-1800 2900);
DISPLAY INVISIBLE (-1800 2900);
FORCEPROP 2 LAST CDS_LIB pure_quanta
R 2
J 0
(-1800 2900);
DISPLAY INVISIBLE (-1800 2900);
FORCEPROP 2 LAST SEC_TYPE TH
R 2
J 0
(-1675 2475);
DISPLAY 0.680851 (-1675 2475);
DISPLAY INVISIBLE (-1675 2475);
FORCEPROP 1 LAST LOCATION X23
J 0
(-1925 3220);
DISPLAY 0.723404 (-1925 3220);
PAINT GREEN (-1925 3220);
FORCEPROP 0 LASTPIN (-1525 2825) $PN 2
J 0
(-1515 2835);
DISPLAY 0.680851 (-1515 2835);
PAINT MONO (-1515 2835);
FORCEPROP 0 LASTPIN (-1525 2975) $PN 3
J 0
(-1515 2985);
DISPLAY 0.680851 (-1515 2985);
PAINT MONO (-1515 2985);
FORCEPROP 0 LASTPIN (-2075 2825) $PN 1
J 2
(-2085 2835);
DISPLAY 0.680851 (-2085 2835);
PAINT MONO (-2085 2835);
FORCEPROP 0 LASTPIN (-2075 2975) $PN 4
J 2
(-2085 2985);
DISPLAY 0.680851 (-2085 2985);
PAINT MONO (-2085 2985);
FORCEPROP 2 LAST SEC 1
R 2
J 0
(-1675 2475);
DISPLAY 0.680851 (-1675 2475);
PAINT MONO (-1675 2475);
DISPLAY INVISIBLE (-1675 2475);
FORCEADD TDR_3P..2
(-8500 3800);
FORCEPROP 1 LAST PACK_TYPE TH2
J 2
(-8475 3950);
DISPLAY 0.872340 (-8475 3950);
FORCEPROP 1 LAST PATH I5
J 2
(-8200 3950);
DISPLAY 0.872340 (-8200 3950);
PAINT PINK (-8200 3950);
DISPLAY INVISIBLE (-8200 3950);
FORCEPROP 1 LAST CDS_LMAN_SYM_OUTLINE -150,100,50,-100
J 0
(-8500 3800);
DISPLAY 0.468085 (-8500 3800);
PAINT GREEN (-8500 3800);
DISPLAY INVISIBLE (-8500 3800);
FORCEPROP 2 LAST CDS_LIB pure_quanta
J 0
(-8500 3800);
DISPLAY INVISIBLE (-8500 3800);
FORCEPROP 1 LAST PART_NUMBER N_A
J 1
(-8440 3650);
DISPLAY 0.872340 (-8440 3650);
PAINT PINK (-8440 3650);
DISPLAY INVISIBLE (-8440 3650);
FORCEPROP 1 LAST MATERIAL EMPTY
J 2
(-8500 3950);
DISPLAY 0.872340 (-8500 3950);
PAINT PINK (-8500 3950);
DISPLAY INVISIBLE (-8500 3950);
FORCEPROP 2 LAST SEC_TYPE TH2
J 0
(-8475 4050);
DISPLAY 0.680851 (-8475 4050);
DISPLAY INVISIBLE (-8475 4050);
FORCEPROP 1 LAST LOCATION DB5
J 2
(-8475 4000);
DISPLAY 0.872340 (-8475 4000);
PAINT PINK (-8475 4000);
FORCEPROP 0 LASTPIN (-8700 3800) $PN 1
J 2
(-8710 3810);
DISPLAY 0.680851 (-8710 3810);
PAINT MONO (-8710 3810);
FORCEPROP 0 LASTPIN (-8400 3850) $PN 2
J 0
(-8390 3860);
DISPLAY 0.680851 (-8390 3860);
PAINT MONO (-8390 3860);
FORCEPROP 0 LASTPIN (-8400 3750) $PN 3
J 0
(-8390 3760);
DISPLAY 0.680851 (-8390 3760);
PAINT MONO (-8390 3760);
FORCEPROP 2 LAST SEC 1
J 0
(-8475 4050);
DISPLAY 0.680851 (-8475 4050);
PAINT MONO (-8475 4050);
DISPLAY INVISIBLE (-8475 4050);
FORCEADD TP_TDR_4P_FTS..1
(-3325 5000);
FORCEPROP 2 LAST PACK_TYPE TH
J 0
(-3450 5325);
DISPLAY 0.680851 (-3450 5325);
FORCEPROP 2 LAST VALUE TP_TDR_4P_DIP
J 0
(-3450 5375);
DISPLAY 0.680851 (-3450 5375);
FORCEPROP 1 LAST PART_NUMBER TP15
J 0
(-3450 5235);
DISPLAY 0.723404 (-3450 5235);
PAINT GREEN (-3450 5235);
FORCEPROP 1 LAST MATERIAL EMPTY
J 0
(-3450 5185);
DISPLAY 0.723404 (-3450 5185);
PAINT GREEN (-3450 5185);
FORCEPROP 1 LAST PATH I58
J 0
(-3225 5180);
DISPLAY 0.723404 (-3225 5180);
PAINT GREEN (-3225 5180);
DISPLAY INVISIBLE (-3225 5180);
FORCEPROP 2 LAST SEC_TYPE TH
J 0
(-3450 5425);
DISPLAY 0.680851 (-3450 5425);
DISPLAY INVISIBLE (-3450 5425);
FORCEPROP 2 LAST CDS_LIB pure_quanta
J 0
(-3325 5000);
DISPLAY INVISIBLE (-3325 5000);
FORCEPROP 1 LAST NEEDS_NO_SIZE TRUE
J 0
(-3325 5000);
DISPLAY 0.468085 (-3325 5000);
PAINT GREEN (-3325 5000);
DISPLAY INVISIBLE (-3325 5000);
FORCEPROP 1 LAST LOCATION X14
J 0
(-3450 5280);
DISPLAY 0.723404 (-3450 5280);
PAINT GREEN (-3450 5280);
FORCEPROP 0 LASTPIN (-3600 5075) $PN 2
J 2
(-3610 5085);
DISPLAY 0.680851 (-3610 5085);
PAINT MONO (-3610 5085);
FORCEPROP 0 LASTPIN (-3600 4925) $PN 3
J 2
(-3610 4935);
DISPLAY 0.680851 (-3610 4935);
PAINT MONO (-3610 4935);
FORCEPROP 0 LASTPIN (-3050 5075) $PN 1
J 0
(-3040 5085);
DISPLAY 0.680851 (-3040 5085);
PAINT MONO (-3040 5085);
FORCEPROP 0 LASTPIN (-3050 4925) $PN 4
J 0
(-3040 4935);
DISPLAY 0.680851 (-3040 4935);
PAINT MONO (-3040 4935);
FORCEPROP 2 LAST SEC 1
J 0
(-3450 5425);
DISPLAY 0.680851 (-3450 5425);
PAINT MONO (-3450 5425);
DISPLAY INVISIBLE (-3450 5425);
FORCEADD TP_TDR_4P_FTS..1
R 4
(-1800 5000);
FORCEPROP 2 LAST PACK_TYPE TH
J 0
(-1925 5275);
DISPLAY 0.680851 (-1925 5275);
FORCEPROP 1 LAST MATERIAL EMPTY
J 0
(-1925 5415);
DISPLAY 0.723404 (-1925 5415);
PAINT GREEN (-1925 5415);
FORCEPROP 2 LAST VALUE TP_TDR_4P_DIP
J 0
(-1925 5225);
DISPLAY 0.680851 (-1925 5225);
FORCEPROP 1 LAST PART_NUMBER TP15
J 0
(-1925 5365);
DISPLAY 0.723404 (-1925 5365);
PAINT GREEN (-1925 5365);
FORCEPROP 1 LAST PATH I59
R 2
J 0
(-1900 4820);
DISPLAY 0.723404 (-1900 4820);
PAINT GREEN (-1900 4820);
DISPLAY INVISIBLE (-1900 4820);
FORCEPROP 1 LAST NEEDS_NO_SIZE TRUE
R 2
J 0
(-1800 5000);
DISPLAY 0.468085 (-1800 5000);
PAINT GREEN (-1800 5000);
DISPLAY INVISIBLE (-1800 5000);
FORCEPROP 2 LAST CDS_LIB pure_quanta
R 2
J 0
(-1800 5000);
DISPLAY INVISIBLE (-1800 5000);
FORCEPROP 2 LAST SEC_TYPE TH
R 2
J 0
(-1675 4575);
DISPLAY 0.680851 (-1675 4575);
DISPLAY INVISIBLE (-1675 4575);
FORCEPROP 1 LAST LOCATION X20
J 0
(-1925 5320);
DISPLAY 0.723404 (-1925 5320);
PAINT GREEN (-1925 5320);
FORCEPROP 0 LASTPIN (-1525 4925) $PN 2
J 0
(-1515 4935);
DISPLAY 0.680851 (-1515 4935);
PAINT MONO (-1515 4935);
FORCEPROP 0 LASTPIN (-1525 5075) $PN 3
J 0
(-1515 5085);
DISPLAY 0.680851 (-1515 5085);
PAINT MONO (-1515 5085);
FORCEPROP 0 LASTPIN (-2075 4925) $PN 1
J 2
(-2085 4935);
DISPLAY 0.680851 (-2085 4935);
PAINT MONO (-2085 4935);
FORCEPROP 0 LASTPIN (-2075 5075) $PN 4
J 2
(-2085 5085);
DISPLAY 0.680851 (-2085 5085);
PAINT MONO (-2085 5085);
FORCEPROP 2 LAST SEC 1
R 2
J 0
(-1675 4575);
DISPLAY 0.680851 (-1675 4575);
PAINT MONO (-1675 4575);
DISPLAY INVISIBLE (-1675 4575);
FORCEADD UNIVERSAL_GND..1
(-8975 3525);
FORCEPROP 3 LASTPIN (-8975 3575) SIG_NAME T_GND\g
J 0
(-8965 3585);
DISPLAY 0.659574 (-8965 3585);
PAINT MONO (-8965 3585);
DISPLAY INVISIBLE (-8965 3585);
FORCEPROP 1 LAST HDL_POWER T_GND
J 1
(-8950 3450);
DISPLAY 0.702128 (-8950 3450);
PAINT GREEN (-8950 3450);
FORCEPROP 1 LAST PATH I6
J 0
(-8900 3525);
DISPLAY 0.872340 (-8900 3525);
PAINT AQUA (-8900 3525);
DISPLAY INVISIBLE (-8900 3525);
FORCEPROP 2 LAST CDS_LIB logical_power
J 0
(-8975 3525);
DISPLAY INVISIBLE (-8975 3525);
FORCEADD UNIVERSAL_GND..1
(-6850 4700);
FORCEPROP 3 LASTPIN (-6850 4750) SIG_NAME GND_P1\g
J 0
(-6840 4760);
DISPLAY 0.659574 (-6840 4760);
PAINT MONO (-6840 4760);
DISPLAY INVISIBLE (-6840 4760);
FORCEPROP 1 LAST HDL_POWER GND_P1
J 1
(-6825 4625);
DISPLAY 0.702128 (-6825 4625);
PAINT GREEN (-6825 4625);
FORCEPROP 1 LAST PATH I61
J 0
(-6775 4700);
DISPLAY 0.872340 (-6775 4700);
PAINT AQUA (-6775 4700);
DISPLAY INVISIBLE (-6775 4700);
FORCEPROP 2 LAST CDS_LIB logical_power
J 0
(-6850 4700);
DISPLAY INVISIBLE (-6850 4700);
FORCEADD UNIVERSAL_GND..1
(-6850 5400);
FORCEPROP 3 LASTPIN (-6850 5450) SIG_NAME GND_P1\g
J 0
(-6840 5460);
DISPLAY 0.659574 (-6840 5460);
PAINT MONO (-6840 5460);
DISPLAY INVISIBLE (-6840 5460);
FORCEPROP 1 LAST HDL_POWER GND_P1
J 1
(-6825 5325);
DISPLAY 0.702128 (-6825 5325);
PAINT GREEN (-6825 5325);
FORCEPROP 1 LAST PATH I62
J 0
(-6775 5400);
DISPLAY 0.872340 (-6775 5400);
PAINT AQUA (-6775 5400);
DISPLAY INVISIBLE (-6775 5400);
FORCEPROP 2 LAST CDS_LIB logical_power
J 0
(-6850 5400);
DISPLAY INVISIBLE (-6850 5400);
FORCEADD UNIVERSAL_GND..1
(-4550 5400);
FORCEPROP 3 LASTPIN (-4550 5450) SIG_NAME GND_P1\g
J 0
(-4540 5460);
DISPLAY 0.659574 (-4540 5460);
PAINT MONO (-4540 5460);
DISPLAY INVISIBLE (-4540 5460);
FORCEPROP 1 LAST HDL_POWER GND_P1
J 1
(-4525 5325);
DISPLAY 0.702128 (-4525 5325);
PAINT GREEN (-4525 5325);
FORCEPROP 1 LAST PATH I63
J 0
(-4475 5400);
DISPLAY 0.872340 (-4475 5400);
PAINT AQUA (-4475 5400);
DISPLAY INVISIBLE (-4475 5400);
FORCEPROP 2 LAST CDS_LIB logical_power
J 0
(-4550 5400);
DISPLAY INVISIBLE (-4550 5400);
FORCEADD UNIVERSAL_GND..1
(-4550 4700);
FORCEPROP 3 LASTPIN (-4550 4750) SIG_NAME GND_P1\g
J 0
(-4540 4760);
DISPLAY 0.659574 (-4540 4760);
PAINT MONO (-4540 4760);
DISPLAY INVISIBLE (-4540 4760);
FORCEPROP 1 LAST HDL_POWER GND_P1
J 1
(-4525 4625);
DISPLAY 0.702128 (-4525 4625);
PAINT GREEN (-4525 4625);
FORCEPROP 1 LAST PATH I64
J 0
(-4475 4700);
DISPLAY 0.872340 (-4475 4700);
PAINT AQUA (-4475 4700);
DISPLAY INVISIBLE (-4475 4700);
FORCEPROP 2 LAST CDS_LIB logical_power
J 0
(-4550 4700);
DISPLAY INVISIBLE (-4550 4700);
FORCEADD UNIVERSAL_GND..1
(-3725 4700);
FORCEPROP 3 LASTPIN (-3725 4750) SIG_NAME GND_P1\g
J 0
(-3715 4760);
DISPLAY 0.659574 (-3715 4760);
PAINT MONO (-3715 4760);
DISPLAY INVISIBLE (-3715 4760);
FORCEPROP 1 LAST HDL_POWER GND_P1
J 1
(-3700 4625);
DISPLAY 0.702128 (-3700 4625);
PAINT GREEN (-3700 4625);
FORCEPROP 1 LAST PATH I65
J 0
(-3650 4700);
DISPLAY 0.872340 (-3650 4700);
PAINT AQUA (-3650 4700);
DISPLAY INVISIBLE (-3650 4700);
FORCEPROP 2 LAST CDS_LIB logical_power
J 0
(-3725 4700);
DISPLAY INVISIBLE (-3725 4700);
FORCEADD UNIVERSAL_GND..1
(-1425 4700);
FORCEPROP 3 LASTPIN (-1425 4750) SIG_NAME GND_P1\g
J 0
(-1415 4760);
DISPLAY 0.659574 (-1415 4760);
PAINT MONO (-1415 4760);
DISPLAY INVISIBLE (-1415 4760);
FORCEPROP 1 LAST HDL_POWER GND_P1
J 1
(-1400 4625);
DISPLAY 0.702128 (-1400 4625);
PAINT GREEN (-1400 4625);
FORCEPROP 1 LAST PATH I66
J 0
(-1350 4700);
DISPLAY 0.872340 (-1350 4700);
PAINT AQUA (-1350 4700);
DISPLAY INVISIBLE (-1350 4700);
FORCEPROP 2 LAST CDS_LIB logical_power
J 0
(-1425 4700);
DISPLAY INVISIBLE (-1425 4700);
FORCEADD UNIVERSAL_GND..1
(-1425 5400);
FORCEPROP 3 LASTPIN (-1425 5450) SIG_NAME GND_P1\g
J 0
(-1415 5460);
DISPLAY 0.659574 (-1415 5460);
PAINT MONO (-1415 5460);
DISPLAY INVISIBLE (-1415 5460);
FORCEPROP 1 LAST HDL_POWER GND_P1
J 1
(-1400 5325);
DISPLAY 0.702128 (-1400 5325);
PAINT GREEN (-1400 5325);
FORCEPROP 1 LAST PATH I67
J 0
(-1350 5400);
DISPLAY 0.872340 (-1350 5400);
PAINT AQUA (-1350 5400);
DISPLAY INVISIBLE (-1350 5400);
FORCEPROP 2 LAST CDS_LIB logical_power
J 0
(-1425 5400);
DISPLAY INVISIBLE (-1425 5400);
FORCEADD UNIVERSAL_GND..1
(-3725 5400);
FORCEPROP 3 LASTPIN (-3725 5450) SIG_NAME GND_P1\g
J 0
(-3715 5460);
DISPLAY 0.659574 (-3715 5460);
PAINT MONO (-3715 5460);
DISPLAY INVISIBLE (-3715 5460);
FORCEPROP 1 LAST HDL_POWER GND_P1
J 1
(-3700 5325);
DISPLAY 0.702128 (-3700 5325);
PAINT GREEN (-3700 5325);
FORCEPROP 1 LAST PATH I68
J 0
(-3650 5400);
DISPLAY 0.872340 (-3650 5400);
PAINT AQUA (-3650 5400);
DISPLAY INVISIBLE (-3650 5400);
FORCEPROP 2 LAST CDS_LIB logical_power
J 0
(-3725 5400);
DISPLAY INVISIBLE (-3725 5400);
FORCEADD UNIVERSAL_GND..1
(-1425 2600);
FORCEPROP 3 LASTPIN (-1425 2650) SIG_NAME GND_P1\g
J 0
(-1415 2660);
DISPLAY 0.659574 (-1415 2660);
PAINT MONO (-1415 2660);
DISPLAY INVISIBLE (-1415 2660);
FORCEPROP 1 LAST HDL_POWER GND_P1
J 1
(-1400 2525);
DISPLAY 0.702128 (-1400 2525);
PAINT GREEN (-1400 2525);
FORCEPROP 1 LAST PATH I69
J 0
(-1350 2600);
DISPLAY 0.872340 (-1350 2600);
PAINT AQUA (-1350 2600);
DISPLAY INVISIBLE (-1350 2600);
FORCEPROP 2 LAST CDS_LIB logical_power
J 0
(-1425 2600);
DISPLAY INVISIBLE (-1425 2600);
FORCEADD TDR_3P..2
(-8500 4275);
FORCEPROP 1 LAST PACK_TYPE TH2
J 2
(-8475 4425);
DISPLAY 0.872340 (-8475 4425);
FORCEPROP 1 LAST PATH I7
J 2
(-8200 4425);
DISPLAY 0.872340 (-8200 4425);
PAINT PINK (-8200 4425);
DISPLAY INVISIBLE (-8200 4425);
FORCEPROP 1 LAST CDS_LMAN_SYM_OUTLINE -150,100,50,-100
J 0
(-8500 4275);
DISPLAY 0.468085 (-8500 4275);
PAINT GREEN (-8500 4275);
DISPLAY INVISIBLE (-8500 4275);
FORCEPROP 2 LAST CDS_LIB pure_quanta
J 0
(-8500 4275);
DISPLAY INVISIBLE (-8500 4275);
FORCEPROP 1 LAST PART_NUMBER N_A
J 1
(-8440 4125);
DISPLAY 0.872340 (-8440 4125);
PAINT PINK (-8440 4125);
DISPLAY INVISIBLE (-8440 4125);
FORCEPROP 1 LAST MATERIAL EMPTY
J 2
(-8500 4425);
DISPLAY 0.872340 (-8500 4425);
PAINT PINK (-8500 4425);
DISPLAY INVISIBLE (-8500 4425);
FORCEPROP 2 LAST SEC_TYPE TH2
J 0
(-8475 4525);
DISPLAY 0.680851 (-8475 4525);
DISPLAY INVISIBLE (-8475 4525);
FORCEPROP 1 LAST LOCATION DB4
J 2
(-8475 4475);
DISPLAY 0.872340 (-8475 4475);
PAINT PINK (-8475 4475);
FORCEPROP 0 LASTPIN (-8700 4275) $PN 1
J 2
(-8710 4285);
DISPLAY 0.680851 (-8710 4285);
PAINT MONO (-8710 4285);
FORCEPROP 0 LASTPIN (-8400 4325) $PN 2
J 0
(-8390 4335);
DISPLAY 0.680851 (-8390 4335);
PAINT MONO (-8390 4335);
FORCEPROP 0 LASTPIN (-8400 4225) $PN 3
J 0
(-8390 4235);
DISPLAY 0.680851 (-8390 4235);
PAINT MONO (-8390 4235);
FORCEPROP 2 LAST SEC 1
J 0
(-8475 4525);
DISPLAY 0.680851 (-8475 4525);
PAINT MONO (-8475 4525);
DISPLAY INVISIBLE (-8475 4525);
FORCEADD UNIVERSAL_GND..1
(-3725 2600);
FORCEPROP 3 LASTPIN (-3725 2650) SIG_NAME GND_P1\g
J 0
(-3715 2660);
DISPLAY 0.659574 (-3715 2660);
PAINT MONO (-3715 2660);
DISPLAY INVISIBLE (-3715 2660);
FORCEPROP 1 LAST HDL_POWER GND_P1
J 1
(-3700 2525);
DISPLAY 0.702128 (-3700 2525);
PAINT GREEN (-3700 2525);
FORCEPROP 1 LAST PATH I70
J 0
(-3650 2600);
DISPLAY 0.872340 (-3650 2600);
PAINT AQUA (-3650 2600);
DISPLAY INVISIBLE (-3650 2600);
FORCEPROP 2 LAST CDS_LIB logical_power
J 0
(-3725 2600);
DISPLAY INVISIBLE (-3725 2600);
FORCEADD UNIVERSAL_GND..1
(-3725 1900);
FORCEPROP 3 LASTPIN (-3725 1950) SIG_NAME GND_P1\g
J 0
(-3715 1960);
DISPLAY 0.659574 (-3715 1960);
PAINT MONO (-3715 1960);
DISPLAY INVISIBLE (-3715 1960);
FORCEPROP 1 LAST HDL_POWER GND_P1
J 1
(-3700 1825);
DISPLAY 0.702128 (-3700 1825);
PAINT GREEN (-3700 1825);
FORCEPROP 1 LAST PATH I71
J 0
(-3650 1900);
DISPLAY 0.872340 (-3650 1900);
PAINT AQUA (-3650 1900);
DISPLAY INVISIBLE (-3650 1900);
FORCEPROP 2 LAST CDS_LIB logical_power
J 0
(-3725 1900);
DISPLAY INVISIBLE (-3725 1900);
FORCEADD UNIVERSAL_GND..1
(-1425 1900);
FORCEPROP 3 LASTPIN (-1425 1950) SIG_NAME GND_P1\g
J 0
(-1415 1960);
DISPLAY 0.659574 (-1415 1960);
PAINT MONO (-1415 1960);
DISPLAY INVISIBLE (-1415 1960);
FORCEPROP 1 LAST HDL_POWER GND_P1
J 1
(-1400 1825);
DISPLAY 0.702128 (-1400 1825);
PAINT GREEN (-1400 1825);
FORCEPROP 1 LAST PATH I72
J 0
(-1350 1900);
DISPLAY 0.872340 (-1350 1900);
PAINT AQUA (-1350 1900);
DISPLAY INVISIBLE (-1350 1900);
FORCEPROP 2 LAST CDS_LIB logical_power
J 0
(-1425 1900);
DISPLAY INVISIBLE (-1425 1900);
FORCEADD UNIVERSAL_GND..1
(-4550 1900);
FORCEPROP 3 LASTPIN (-4550 1950) SIG_NAME GND_P1\g
J 0
(-4540 1960);
DISPLAY 0.659574 (-4540 1960);
PAINT MONO (-4540 1960);
DISPLAY INVISIBLE (-4540 1960);
FORCEPROP 1 LAST HDL_POWER GND_P1
J 1
(-4525 1825);
DISPLAY 0.702128 (-4525 1825);
PAINT GREEN (-4525 1825);
FORCEPROP 1 LAST PATH I73
J 0
(-4475 1900);
DISPLAY 0.872340 (-4475 1900);
PAINT AQUA (-4475 1900);
DISPLAY INVISIBLE (-4475 1900);
FORCEPROP 2 LAST CDS_LIB logical_power
J 0
(-4550 1900);
DISPLAY INVISIBLE (-4550 1900);
FORCEADD UNIVERSAL_GND..1
(-6850 1900);
FORCEPROP 3 LASTPIN (-6850 1950) SIG_NAME GND_P1\g
J 0
(-6840 1960);
DISPLAY 0.659574 (-6840 1960);
PAINT MONO (-6840 1960);
DISPLAY INVISIBLE (-6840 1960);
FORCEPROP 1 LAST HDL_POWER GND_P1
J 1
(-6825 1825);
DISPLAY 0.702128 (-6825 1825);
PAINT GREEN (-6825 1825);
FORCEPROP 1 LAST PATH I74
J 0
(-6775 1900);
DISPLAY 0.872340 (-6775 1900);
PAINT AQUA (-6775 1900);
DISPLAY INVISIBLE (-6775 1900);
FORCEPROP 2 LAST CDS_LIB logical_power
J 0
(-6850 1900);
DISPLAY INVISIBLE (-6850 1900);
FORCEADD UNIVERSAL_GND..1
(-6850 2600);
FORCEPROP 3 LASTPIN (-6850 2650) SIG_NAME GND_P1\g
J 0
(-6840 2660);
DISPLAY 0.659574 (-6840 2660);
PAINT MONO (-6840 2660);
DISPLAY INVISIBLE (-6840 2660);
FORCEPROP 1 LAST HDL_POWER GND_P1
J 1
(-6825 2525);
DISPLAY 0.702128 (-6825 2525);
PAINT GREEN (-6825 2525);
FORCEPROP 1 LAST PATH I75
J 0
(-6775 2600);
DISPLAY 0.872340 (-6775 2600);
PAINT AQUA (-6775 2600);
DISPLAY INVISIBLE (-6775 2600);
FORCEPROP 2 LAST CDS_LIB logical_power
J 0
(-6850 2600);
DISPLAY INVISIBLE (-6850 2600);
FORCEADD UNIVERSAL_GND..1
(-4550 2600);
FORCEPROP 3 LASTPIN (-4550 2650) SIG_NAME GND_P1\g
J 0
(-4540 2660);
DISPLAY 0.659574 (-4540 2660);
PAINT MONO (-4540 2660);
DISPLAY INVISIBLE (-4540 2660);
FORCEPROP 1 LAST HDL_POWER GND_P1
J 1
(-4525 2525);
DISPLAY 0.702128 (-4525 2525);
PAINT GREEN (-4525 2525);
FORCEPROP 1 LAST PATH I76
J 0
(-4475 2600);
DISPLAY 0.872340 (-4475 2600);
PAINT AQUA (-4475 2600);
DISPLAY INVISIBLE (-4475 2600);
FORCEPROP 2 LAST CDS_LIB logical_power
J 0
(-4550 2600);
DISPLAY INVISIBLE (-4550 2600);
FORCEADD UNIVERSAL_GND..1
(-8975 4000);
FORCEPROP 3 LASTPIN (-8975 4050) SIG_NAME T_GND\g
J 0
(-8965 4060);
DISPLAY 0.659574 (-8965 4060);
PAINT MONO (-8965 4060);
DISPLAY INVISIBLE (-8965 4060);
FORCEPROP 1 LAST HDL_POWER T_GND
J 1
(-8950 3925);
DISPLAY 0.702128 (-8950 3925);
PAINT GREEN (-8950 3925);
FORCEPROP 1 LAST PATH I8
J 0
(-8900 4000);
DISPLAY 0.872340 (-8900 4000);
PAINT AQUA (-8900 4000);
DISPLAY INVISIBLE (-8900 4000);
FORCEPROP 2 LAST CDS_LIB logical_power
J 0
(-8975 4000);
DISPLAY INVISIBLE (-8975 4000);
FORCEADD TDR_3P..2
(-8500 4750);
FORCEPROP 1 LAST PACK_TYPE TH2
J 2
(-8475 4900);
DISPLAY 0.872340 (-8475 4900);
FORCEPROP 1 LAST PATH I9
J 2
(-8200 4900);
DISPLAY 0.872340 (-8200 4900);
PAINT PINK (-8200 4900);
DISPLAY INVISIBLE (-8200 4900);
FORCEPROP 1 LAST CDS_LMAN_SYM_OUTLINE -150,100,50,-100
J 0
(-8500 4750);
DISPLAY 0.468085 (-8500 4750);
PAINT GREEN (-8500 4750);
DISPLAY INVISIBLE (-8500 4750);
FORCEPROP 2 LAST CDS_LIB pure_quanta
J 0
(-8500 4750);
DISPLAY INVISIBLE (-8500 4750);
FORCEPROP 1 LAST PART_NUMBER N_A
J 1
(-8440 4600);
DISPLAY 0.872340 (-8440 4600);
PAINT PINK (-8440 4600);
DISPLAY INVISIBLE (-8440 4600);
FORCEPROP 1 LAST MATERIAL EMPTY
J 2
(-8500 4900);
DISPLAY 0.872340 (-8500 4900);
PAINT PINK (-8500 4900);
DISPLAY INVISIBLE (-8500 4900);
FORCEPROP 2 LAST SEC_TYPE TH2
J 0
(-8475 5000);
DISPLAY 0.680851 (-8475 5000);
DISPLAY INVISIBLE (-8475 5000);
FORCEPROP 1 LAST LOCATION DB3
J 2
(-8475 4950);
DISPLAY 0.872340 (-8475 4950);
PAINT PINK (-8475 4950);
FORCEPROP 0 LASTPIN (-8700 4750) $PN 1
J 2
(-8710 4760);
DISPLAY 0.680851 (-8710 4760);
PAINT MONO (-8710 4760);
FORCEPROP 0 LASTPIN (-8400 4800) $PN 2
J 0
(-8390 4810);
DISPLAY 0.680851 (-8390 4810);
PAINT MONO (-8390 4810);
FORCEPROP 0 LASTPIN (-8400 4700) $PN 3
J 0
(-8390 4710);
DISPLAY 0.680851 (-8390 4710);
PAINT MONO (-8390 4710);
FORCEPROP 2 LAST SEC 1
J 0
(-8475 5000);
DISPLAY 0.680851 (-8475 5000);
PAINT MONO (-8475 5000);
DISPLAY INVISIBLE (-8475 5000);
FORCEADD QUANTA_TITLE_BLOCK_C..1
(0 0);
FORCEPROP 0 LAST CDS_CON_LAST_MODIFIED Fri Aug 25 17:25:50 2023
J 0
(-1885 15);
DISPLAY INVISIBLE (-1885 15);
FORCEPROP 2 LAST Q_DEPT 
J 1
(-3763 49);
DISPLAY 1.957447 (-3763 49);
PAINT GREEN (-3763 49);
FORCEPROP 1 LAST CUSTOM_TXT_CDS <CON_LAST_MODIFIED>
J 0
(-1885 15);
DISPLAY 0.978723 (-1885 15);
FORCEPROP 2 LAST CUSTOM_TXT_CDS <XR_PAGE_TITLE>
J 0
(-7890 5250);
DISPLAY 0.638298 (-7890 5250);
PAINT PINK (-7890 5250);
DISPLAY INVISIBLE (-7890 5250);
FORCEPROP 1 LAST CUSTOM_TXT_CDS <NAME_2>
J 0
(-3175 50);
FORCEPROP 1 LAST CUSTOM_TXT_CDS <NAME_1>
J 0
(-3175 175);
FORCEPROP 1 LAST CUSTOM_TXT_CDS <Q_NUMBER>
J 0
(-1403 103);
DISPLAY 1.212766 (-1403 103);
FORCEPROP 1 LAST CUSTOM_TXT_CDS <Q_PROJ>
J 0
(-2382 102);
DISPLAY 1.212766 (-2382 102);
FORCEPROP 1 LAST CUSTOM_TXT_CDS <Q_REV>
J 0
(-184 103);
DISPLAY 1.212766 (-184 103);
FORCEPROP 1 LAST CUSTOM_TXT_CDS <CON_PAGE_NUM> OF <CON_TOTAL_PAGES>
J 0
(-446 18);
DISPLAY 0.978723 (-446 18);
FORCEPROP 1 LAST Q_TITLE TDR
J 0
(-9366 26);
DISPLAY 2.446809 (-9366 26);
PAINT GREEN (-9366 26);
FORCEPROP 1 LAST COMMENT_BODY TRUE
J 0
(12 -13);
DISPLAY 0.978723 (12 -13);
PAINT GREEN (12 -13);
DISPLAY INVISIBLE (12 -13);
FORCEPROP 2 LAST PAGE_BORDER TRUE
J 0
(-7890 5250);
DISPLAY 0.638298 (-7890 5250);
PAINT PINK (-7890 5250);
DISPLAY INVISIBLE (-7890 5250);
FORCEPROP 2 LAST CDS_LIB pure_quanta
J 0
(0 0);
DISPLAY INVISIBLE (0 0);
FORCEPROP 1 LAST CDS_LMAN_SYM_OUTLINE -9475,6775,100,-125
J 0
(0 0);
DISPLAY 0.468085 (0 0);
PAINT GREEN (0 0);
DISPLAY INVISIBLE (0 0);
FORCEPROP 2 LAST CDS_XR_PAGE_TITLE CR-60 : @SCM_LIB.SCM(SCH_1):PAGE60
J 0
(-7890 5250);
DISPLAY 0.638298 (-7890 5250);
PAINT PINK (-7890 5250);
DISPLAY INVISIBLE (-7890 5250);
WIRE 16 -1 (-8975 5475)(-8975 5700);
WIRE 16 -1 (-8975 5000)(-8975 5225);
WIRE 16 -1 (-8975 4525)(-8975 4750);
WIRE 16 -1 (-8975 4050)(-8975 4275);
WIRE 16 -1 (-8975 3100)(-8975 3325);
WIRE 16 -1 (-8975 3575)(-8975 3800);
WIRE 16 -1 (-6850 4750)(-6850 4925);
WIRE 16 -1 (-6850 5450)(-6850 5625);
WIRE 16 -1 (-4550 5450)(-4550 5625);
WIRE 16 -1 (-4550 4750)(-4550 4925);
WIRE 16 -1 (-3725 4750)(-3725 4925);
WIRE 16 -1 (-1425 5450)(-1425 5625);
WIRE 16 -1 (-3725 5450)(-3725 5625);
WIRE 16 -1 (-1425 4750)(-1425 4925);
WIRE 16 -1 (-1425 2650)(-1425 2825);
WIRE 16 -1 (-3725 2650)(-3725 2825);
WIRE 16 -1 (-3725 1950)(-3725 2125);
WIRE 16 -1 (-1425 1950)(-1425 2125);
WIRE 16 -1 (-4550 1950)(-4550 2125);
WIRE 16 -1 (-6850 1950)(-6850 2125);
WIRE 16 -1 (-6850 2650)(-6850 2825);
WIRE 16 -1 (-4550 2650)(-4550 2825);
WIRE 16 -1 (-8975 4750)(-8700 4750);
WIRE 16 -1 (-8975 5225)(-8700 5225);
WIRE 16 -1 (-8975 5700)(-8700 5700);
WIRE 16 -1 (-8975 3325)(-8700 3325);
WIRE 16 -1 (-8975 3800)(-8700 3800);
WIRE 16 -1 (-6725 4925)(-6850 4925);
WIRE 16 -1 (-6850 4925)(-6850 5075);
WIRE 16 -1 (-6850 5075)(-6725 5075);
WIRE 16 -1 (-6725 5625)(-6850 5625);
WIRE 16 -1 (-6850 5625)(-6850 5775);
WIRE 16 -1 (-6850 5775)(-6725 5775);
WIRE 16 -1 (-4550 5775)(-4650 5775);
WIRE 16 -1 (-4650 5625)(-4550 5625);
WIRE 16 -1 (-4550 5625)(-4550 5775);
WIRE 16 -1 (-4550 5075)(-4650 5075);
WIRE 16 -1 (-4650 4925)(-4550 4925);
WIRE 16 -1 (-4550 4925)(-4550 5075);
WIRE 16 -1 (-3600 4925)(-3725 4925);
WIRE 16 -1 (-3725 4925)(-3725 5075);
WIRE 16 -1 (-3725 5075)(-3600 5075);
WIRE 16 -1 (-1525 4925)(-1425 4925);
WIRE 16 -1 (-1425 4925)(-1425 5075);
WIRE 16 -1 (-1425 5075)(-1525 5075);
WIRE 16 -1 (-1525 5625)(-1425 5625);
WIRE 16 -1 (-1425 5625)(-1425 5775);
WIRE 16 -1 (-1425 5775)(-1525 5775);
WIRE 16 -1 (-3600 5625)(-3725 5625);
WIRE 16 -1 (-3725 5625)(-3725 5775);
WIRE 16 -1 (-3725 5775)(-3600 5775);
WIRE 16 -1 (-1525 2825)(-1425 2825);
WIRE 16 -1 (-1425 2825)(-1425 2975);
WIRE 16 -1 (-1425 2975)(-1525 2975);
WIRE 16 -1 (-3600 2825)(-3725 2825);
WIRE 16 -1 (-3725 2825)(-3725 2975);
WIRE 16 -1 (-3725 2975)(-3600 2975);
WIRE 16 -1 (-3600 2125)(-3725 2125);
WIRE 16 -1 (-3725 2125)(-3725 2275);
WIRE 16 -1 (-3725 2275)(-3600 2275);
WIRE 16 -1 (-1525 2125)(-1425 2125);
WIRE 16 -1 (-1425 2125)(-1425 2275);
WIRE 16 -1 (-1425 2275)(-1525 2275);
WIRE 16 -1 (-4550 2275)(-4650 2275);
WIRE 16 -1 (-4650 2125)(-4550 2125);
WIRE 16 -1 (-4550 2125)(-4550 2275);
WIRE 16 -1 (-6850 2275)(-6725 2275);
WIRE 16 -1 (-6725 2125)(-6850 2125);
WIRE 16 -1 (-6850 2125)(-6850 2275);
WIRE 16 -1 (-6725 2825)(-6850 2825);
WIRE 16 -1 (-6850 2825)(-6850 2975);
WIRE 16 -1 (-6850 2975)(-6725 2975);
WIRE 16 -1 (-4550 2975)(-4650 2975);
WIRE 16 -1 (-4650 2825)(-4550 2825);
WIRE 16 -1 (-4550 2825)(-4550 2975);
WIRE 16 -1 (-8975 4275)(-8700 4275);
WIRE 16 -1 (-7575 4700)(-8400 4700);
WIRE 16 -1 (-8400 4800)(-7575 4800);
FORCEPROP 2 LAST SIG_NAME TDR_SE_50_OHM_IN2
J 0
(-8285 4810);
DISPLAY 0.851064 (-8285 4810);
WIRE 16 -1 (-7575 4800)(-7575 4700);
WIRE 16 -1 (-7575 5175)(-8400 5175);
WIRE 16 -1 (-8400 5275)(-7575 5275);
FORCEPROP 2 LAST SIG_NAME TDR_SE_50_OHM_IN1
J 0
(-8285 5285);
DISPLAY 0.851064 (-8285 5285);
WIRE 16 -1 (-7575 5275)(-7575 5175);
WIRE 16 -1 (-6175 2275)(-5200 2275);
FORCEPROP 2 LAST SIG_NAME TDR_DIFF_85_BOT_DP
J 0
(-6035 2310);
DISPLAY 0.851064 (-6035 2310);
WIRE 16 -1 (-6175 2125)(-5200 2125);
FORCEPROP 2 LAST SIG_NAME TDR_DIFF_85_BOT_DN
J 0
(-6035 2160);
DISPLAY 0.851064 (-6035 2160);
WIRE 16 -1 (-6175 2975)(-5200 2975);
FORCEPROP 2 LAST SIG_NAME TDR_DIFF_85_IN4_DP
J 0
(-6035 3010);
DISPLAY 0.851064 (-6035 3010);
WIRE 16 -1 (-6175 2825)(-5200 2825);
FORCEPROP 2 LAST SIG_NAME TDR_DIFF_85_IN4_DN
J 0
(-6035 2860);
DISPLAY 0.851064 (-6035 2860);
WIRE 16 -1 (-6175 5775)(-5200 5775);
FORCEPROP 2 LAST SIG_NAME TDR_DIFF_85_TOP_DP
J 0
(-6035 5810);
DISPLAY 0.851064 (-6035 5810);
WIRE 16 -1 (-6175 5625)(-5200 5625);
FORCEPROP 2 LAST SIG_NAME TDR_DIFF_85_TOP_DN
J 0
(-6035 5660);
DISPLAY 0.851064 (-6035 5660);
WIRE 16 -1 (-3050 2275)(-2075 2275);
FORCEPROP 2 LAST SIG_NAME TDR_DIFF_100_BOT_DP
J 0
(-2910 2310);
DISPLAY 0.851064 (-2910 2310);
WIRE 16 -1 (-3050 2125)(-2075 2125);
FORCEPROP 2 LAST SIG_NAME TDR_DIFF_100_BOT_DN
J 0
(-2910 2160);
DISPLAY 0.851064 (-2910 2160);
WIRE 16 -1 (-3050 2975)(-2075 2975);
FORCEPROP 2 LAST SIG_NAME TDR_DIFF_100_IN4_DP
J 0
(-2910 3010);
DISPLAY 0.851064 (-2910 3010);
WIRE 16 -1 (-3050 2825)(-2075 2825);
FORCEPROP 2 LAST SIG_NAME TDR_DIFF_100_IN4_DN
J 0
(-2910 2860);
DISPLAY 0.851064 (-2910 2860);
WIRE 16 -1 (-3050 5075)(-2075 5075);
FORCEPROP 2 LAST SIG_NAME TDR_DIFF_100_IN1_DP
J 0
(-2910 5110);
DISPLAY 0.851064 (-2910 5110);
WIRE 16 -1 (-3050 4925)(-2075 4925);
FORCEPROP 2 LAST SIG_NAME TDR_DIFF_100_IN1_DN
J 0
(-2910 4960);
DISPLAY 0.851064 (-2910 4960);
WIRE 16 -1 (-3050 5625)(-2075 5625);
FORCEPROP 2 LAST SIG_NAME TDR_DIFF_100_TOP_DN
J 0
(-2910 5660);
DISPLAY 0.851064 (-2910 5660);
WIRE 16 -1 (-3050 5775)(-2075 5775);
FORCEPROP 2 LAST SIG_NAME TDR_DIFF_100_TOP_DP
J 0
(-2910 5810);
DISPLAY 0.851064 (-2910 5810);
WIRE 16 -1 (-7575 4225)(-8400 4225);
WIRE 16 -1 (-8400 4325)(-7575 4325);
FORCEPROP 2 LAST SIG_NAME TDR_SE_50_OHM_IN3
J 0
(-8285 4335);
DISPLAY 0.851064 (-8285 4335);
WIRE 16 -1 (-7575 4325)(-7575 4225);
WIRE 16 -1 (-7575 5650)(-8400 5650);
WIRE 16 -1 (-8400 5750)(-7575 5750);
FORCEPROP 2 LAST SIG_NAME TDR_SE_50_OHM_TOP
J 0
(-8285 5760);
DISPLAY 0.851064 (-8285 5760);
WIRE 16 -1 (-7575 5750)(-7575 5650);
WIRE 16 -1 (-7575 3275)(-8400 3275);
WIRE 16 -1 (-8400 3375)(-7575 3375);
FORCEPROP 2 LAST SIG_NAME TDR_SE_50_OHM_BOT
J 0
(-8285 3385);
DISPLAY 0.851064 (-8285 3385);
WIRE 16 -1 (-7575 3375)(-7575 3275);
WIRE 16 -1 (-7575 3750)(-8400 3750);
WIRE 16 -1 (-8400 3850)(-7575 3850);
FORCEPROP 2 LAST SIG_NAME TDR_SE_50_OHM_IN4
J 0
(-8285 3860);
DISPLAY 0.851064 (-8285 3860);
WIRE 16 -1 (-7575 3850)(-7575 3750);
WIRE 16 -1 (-6175 5075)(-5200 5075);
FORCEPROP 2 LAST SIG_NAME TDR_DIFF_85_IN1_DP
J 0
(-6035 5110);
DISPLAY 0.851064 (-6035 5110);
WIRE 16 -1 (-6175 4925)(-5200 4925);
FORCEPROP 2 LAST SIG_NAME TDR_DIFF_85_IN1_DN
J 0
(-6035 4960);
DISPLAY 0.851064 (-6035 4960);
DOT 1 (-1425 4925);
DOT 1 (-3725 4925);
DOT 1 (-1425 2825);
DOT 1 (-3725 2825);
DOT 1 (-1425 2125);
DOT 1 (-3725 2125);
DOT 1 (-3725 5625);
DOT 1 (-1425 5625);
DOT 1 (-4550 5625);
DOT 1 (-6850 5625);
DOT 1 (-6850 4925);
DOT 1 (-4550 4925);
DOT 1 (-6850 2825);
DOT 1 (-4550 2825);
DOT 1 (-6850 2125);
DOT 1 (-4550 2125);
QUIT
